# S9S_MB_2U (Grand Teton) — schematic netlist excerpt (pin names and nets, part order shuffled) for the footprints in the layout excerpt that follows; sources: Cadence DE-HDL packaged netlist, KiCad conversion of 03242023_DA0F0TMBIJ0_F0T_Motherboard_J_brd_V01_OCP.brd

R557  Q_RES  100 1% CHIP  pkg 0402LF  page 45 : A = SVID_DIO0_CPU1_R ; B = PVNN_TERM_CPU1
PC575_P1_2  Q_CAP  22UF 4V 20% X6S  pkg C0805  page 285 : A = PVCCIN_CPU1 ; B = GND

DB16  TDR_3P  EMPTY  pkg TH2  page 309
  GND  = T1_GND
  IO1  = TDR_SE_50_OHM_IN6
  IO2  = TDR_SE_50_OHM_IN6

(kicad_pcb
	(version 20260206)
	(generator "pcbnew")
	(generator_version "10.0")
	(general
		(thickness 1.6)
		(legacy_teardrops no)
	)
	(paper "A4")
	(title_block
		(title "03242023_DA0F0TMBIJ0_F0T_Motherboard_J_brd_V01_OCP.brd")
		(comment 1 "Grand Teton / footprints 5536-5538 of 6105")
	)
	(layers
		(0 "F.Cu" signal "TOP")
		(4 "In1.Cu" signal "GND")
		(6 "In2.Cu" signal "IN1")
		(8 "In3.Cu" signal "GND1")
		(10 "In4.Cu" signal "IN2")
		(12 "In5.Cu" signal "GND2")
		(14 "In6.Cu" signal "IN3")
		(16 "In7.Cu" signal "GND3")
		(18 "In8.Cu" signal "VCC")
		(20 "In9.Cu" signal "VCC1")
		(22 "In10.Cu" signal "GND4")
		(24 "In11.Cu" signal "IN4")
		(26 "In12.Cu" signal "GND5")
		(28 "In13.Cu" signal "IN5")
		(30 "In14.Cu" signal "GND6")
		(32 "In15.Cu" signal "IN6")
		(34 "In16.Cu" signal "GND7")
		(2 "B.Cu" signal "BOTTOM")
		(9 "F.Adhes" user "F.Adhesive")
		(11 "B.Adhes" user "B.Adhesive")
		(13 "F.Paste" user "Package Geometry/Pastemask Top")
		(15 "B.Paste" user "Package Geometry/Pastemask Bottom")
		(5 "F.SilkS" user "Ref Des/Silkscreen Top")
		(7 "B.SilkS" user "Ref Des/Silkscreen Bottom")
		(1 "F.Mask" user "Board Geometry/Soldermask Top")
		(3 "B.Mask" user "Board Geometry/Soldermask Bottom")
		(17 "Dwgs.User" user "User.Drawings")
		(19 "Cmts.User" user "User.Comments")
		(21 "Eco1.User" user "User.Eco1")
		(23 "Eco2.User" user "User.Eco2")
		(25 "Edge.Cuts" user "Board Geometry/Outline")
		(27 "Margin" user)
		(31 "F.CrtYd" user "Package Geometry/Place Bound Top")
		(29 "B.CrtYd" user "Package Geometry/Place Bound Bottom")
		(35 "F.Fab" user "Ref Des/Assembly Top")
		(33 "B.Fab" user "Ref Des/Assembly Bottom")
	)
	(footprint ""
		(layer "B.Cu")
		(at 108.019596 -324.792086 -90)
		(property "Reference" "PC575_P1_2"
			(at 0 0 90)
			(layer "B.SilkS")
			(hide yes)
			(effects
				(font
					(size 1.27 1.27)
				)
				(justify mirror)
			)
		)
		(property "Value" ""
			(at 0 0 90)
			(layer "B.Fab")
			(effects
				(font
					(size 1.27 1.27)
				)
				(justify mirror)
			)
		)
		(duplicate_pad_numbers_are_jumpers no)
		(fp_line
			(start -1.524 0.762)
			(end 1.524 0.762)
			(stroke
				(width 0.1524)
				(type default)
			)
			(layer "B.SilkS")
		)
		(fp_line
			(start 1.524 0.762)
			(end 1.524 -0.762)
			(stroke
				(width 0.1524)
				(type default)
			)
			(layer "B.SilkS")
		)
		(fp_line
			(start -1.524 -0.762)
			(end -1.524 0.762)
			(stroke
				(width 0.1524)
				(type default)
			)
			(layer "B.SilkS")
		)
		(fp_line
			(start 1.524 -0.762)
			(end -1.524 -0.762)
			(stroke
				(width 0.1524)
				(type default)
			)
			(layer "B.SilkS")
		)
		(fp_line
			(start -1.1049 0.724916)
			(end -1.1049 -0.724916)
			(stroke
				(width 0.1)
				(type default)
			)
			(layer "B.Fab")
		)
		(fp_line
			(start 1.1049 0.724916)
			(end -1.1049 0.724916)
			(stroke
				(width 0.1)
				(type default)
			)
			(layer "B.Fab")
		)
		(fp_line
			(start -1.1049 -0.724916)
			(end 1.1049 -0.724916)
			(stroke
				(width 0.1)
				(type default)
			)
			(layer "B.Fab")
		)
		(fp_line
			(start 1.1049 -0.724916)
			(end 1.1049 0.724916)
			(stroke
				(width 0.1)
				(type default)
			)
			(layer "B.Fab")
		)
		(pad "1" smd rect
			(at 0.889 0 270)
			(size 1.016 1.27)
			(layers "B.Cu" "B.Mask" "B.Paste")
			(net "PVCCIN_CPU1")
		)
		(pad "2" smd rect
			(at -0.889 0 270)
			(size 1.016 1.27)
			(layers "B.Cu" "B.Mask" "B.Paste")
			(net "GND")
		)
	)
	(footprint ""
		(layer "B.Cu")
		(at 69.342 -188.469016 -90)
		(property "Reference" "R557"
			(at 0 0 90)
			(layer "B.SilkS")
			(hide yes)
			(effects
				(font
					(size 1.27 1.27)
				)
				(justify mirror)
			)
		)
		(property "Value" ""
			(at 0 0 90)
			(layer "B.Fab")
			(effects
				(font
					(size 1.27 1.27)
				)
				(justify mirror)
			)
		)
		(duplicate_pad_numbers_are_jumpers no)
		(fp_line
			(start -0.7874 0.4064)
			(end 0.7874 0.4064)
			(stroke
				(width 0.1524)
				(type default)
			)
			(layer "B.SilkS")
		)
		(fp_line
			(start 0.7874 0.4064)
			(end 0.7874 -0.4064)
			(stroke
				(width 0.1524)
				(type default)
			)
			(layer "B.SilkS")
		)
		(fp_line
			(start -0.7874 -0.4064)
			(end -0.7874 0.4064)
			(stroke
				(width 0.1524)
				(type default)
			)
			(layer "B.SilkS")
		)
		(fp_line
			(start 0.7874 -0.4064)
			(end -0.7874 -0.4064)
			(stroke
				(width 0.1524)
				(type default)
			)
			(layer "B.SilkS")
		)
		(fp_line
			(start -0.67945 0.3048)
			(end -0.120396 0.3048)
			(stroke
				(width 0.1)
				(type default)
			)
			(layer "B.Fab")
		)
		(fp_line
			(start -0.120396 0.3048)
			(end -0.120396 0.2794)
			(stroke
				(width 0.1)
				(type default)
			)
			(layer "B.Fab")
		)
		(fp_line
			(start 0.12065 0.3048)
			(end 0.67945 0.3048)
			(stroke
				(width 0.1)
				(type default)
			)
			(layer "B.Fab")
		)
		(fp_line
			(start 0.67945 0.3048)
			(end 0.67945 -0.305054)
			(stroke
				(width 0.1)
				(type default)
			)
			(layer "B.Fab")
		)
		(fp_line
			(start -0.120396 0.2794)
			(end 0.12065 0.2794)
			(stroke
				(width 0.1)
				(type default)
			)
			(layer "B.Fab")
		)
		(fp_line
			(start 0.12065 0.2794)
			(end 0.12065 0.3048)
			(stroke
				(width 0.1)
				(type default)
			)
			(layer "B.Fab")
		)
		(fp_line
			(start -0.12065 -0.2794)
			(end -0.12065 -0.3048)
			(stroke
				(width 0.1)
				(type default)
			)
			(layer "B.Fab")
		)
		(fp_line
			(start 0.12065 -0.2794)
			(end -0.12065 -0.2794)
			(stroke
				(width 0.1)
				(type default)
			)
			(layer "B.Fab")
		)
		(fp_line
			(start -0.67945 -0.3048)
			(end -0.67945 0.3048)
			(stroke
				(width 0.1)
				(type default)
			)
			(layer "B.Fab")
		)
		(fp_line
			(start -0.12065 -0.3048)
			(end -0.67945 -0.3048)
			(stroke
				(width 0.1)
				(type default)
			)
			(layer "B.Fab")
		)
		(fp_line
			(start 0.12065 -0.305054)
			(end 0.12065 -0.2794)
			(stroke
				(width 0.1)
				(type default)
			)
			(layer "B.Fab")
		)
		(fp_line
			(start 0.67945 -0.305054)
			(end 0.12065 -0.305054)
			(stroke
				(width 0.1)
				(type default)
			)
			(layer "B.Fab")
		)
		(pad "1" smd circle
			(at 0.40005 0 90)
			(size 0 0)
			(layers "B.Cu" "B.Mask" "B.Paste")
			(net "SVID_DIO0_CPU1_R")
		)
		(pad "2" smd circle
			(at -0.40005 0 90)
			(size 0 0)
			(layers "B.Cu" "B.Mask" "B.Paste")
			(net "PVNN_TERM_CPU1")
		)
	)
	(footprint ""
		(layer "B.Cu")
		(at 477.732344 -334.559656 180)
		(property "Reference" "DB16"
			(at 2.664968 -8.458708 270)
			(unlocked yes)
			(layer "B.SilkS")
			(effects
				(font
					(size 0.7874 0.5842)
					(thickness 0.1524)
				)
				(justify left mirror)
			)
		)
		(property "Value" ""
			(at 0 0 0)
			(layer "B.Fab")
			(effects
				(font
					(size 1.27 1.27)
				)
				(justify mirror)
			)
		)
		(duplicate_pad_numbers_are_jumpers no)
		(fp_line
			(start 3.330702 -4.771136)
			(end -3.330702 -4.771136)
			(stroke
				(width 0.1524)
				(type default)
			)
			(layer "B.SilkS")
		)
		(fp_line
			(start 0 4.011168)
			(end 3.330702 -4.771136)
			(stroke
				(width 0.1524)
				(type default)
			)
			(layer "B.SilkS")
		)
		(fp_line
			(start -3.330702 -4.771136)
			(end 0 4.011168)
			(stroke
				(width 0.1524)
				(type default)
			)
			(layer "B.SilkS")
		)
		(fp_line
			(start 3.330702 -4.771136)
			(end -3.330702 -4.771136)
			(stroke
				(width 0.1)
				(type default)
			)
			(layer "B.Fab")
		)
		(fp_line
			(start 0 4.011168)
			(end 3.330702 -4.771136)
			(stroke
				(width 0.1)
				(type default)
			)
			(layer "B.Fab")
		)
		(fp_line
			(start -3.330702 -4.771136)
			(end 0 4.011168)
			(stroke
				(width 0.1)
				(type default)
			)
			(layer "B.Fab")
		)
		(pad "1" thru_hole circle
			(at 0 0)
			(size 2.159 2.159)
			(drill 1.7018)
			(layers "*.Cu" "*.Mask")
			(remove_unused_layers no)
			(net "T1_GND")
			(clearance 0.0254)
			(thermal_gap 0.0254)
		)
		(pad "2" thru_hole circle
			(at 1.27 -3.348736)
			(size 2.159 2.159)
			(drill 1.7018)
			(layers "*.Cu" "*.Mask")
			(remove_unused_layers no)
			(net "TDR_SE_50_OHM_IN6")
			(clearance 0.0254)
			(thermal_gap 0.0254)
		)
		(pad "3" thru_hole circle
			(at -1.27 -3.348736)
			(size 2.159 2.159)
			(drill 1.7018)
			(layers "*.Cu" "*.Mask")
			(remove_unused_layers no)
			(net "TDR_SE_50_OHM_IN6")
			(clearance 0.0254)
			(thermal_gap 0.0254)
		)
	)
)
